# S9S_MB_2U (Grand Teton) — schematic netlist excerpt (pin names and nets, part order shuffled) for the footprints in the layout excerpt that follows; sources: Cadence DE-HDL packaged netlist, KiCad conversion of 03242023_DA0F0TMBIJ0_F0T_Motherboard_J_brd_V01_OCP.brd

J120  PICOPROBE_BXA  DELTA-L 4.0 EMPTY  pkg TRIANG_LAUNCH_3PXB  page 308
  \1_p\  = DELTA_L_85_10INCH_IN5_DN
  \2_n\  = DELTA_L_85_10INCH_IN5_DP
  \3_g\  = DELTA_L_GND_1

C64  Q_CAP  10UF 16V 10% X6S  pkg C0805  page 102 : A = P12V_S3_AUX_CPU1_NVDIMM ; B = GND

(kicad_pcb
	(version 20260206)
	(generator "pcbnew")
	(generator_version "10.0")
	(general
		(thickness 1.6)
		(legacy_teardrops no)
	)
	(paper "A4")
	(title_block
		(title "03242023_DA0F0TMBIJ0_F0T_Motherboard_J_brd_V01_OCP.brd")
		(comment 1 "Grand Teton / footprints 5088-5089 of 6105")
	)
	(layers
		(0 "F.Cu" signal "TOP")
		(4 "In1.Cu" signal "GND")
		(6 "In2.Cu" signal "IN1")
		(8 "In3.Cu" signal "GND1")
		(10 "In4.Cu" signal "IN2")
		(12 "In5.Cu" signal "GND2")
		(14 "In6.Cu" signal "IN3")
		(16 "In7.Cu" signal "GND3")
		(18 "In8.Cu" signal "VCC")
		(20 "In9.Cu" signal "VCC1")
		(22 "In10.Cu" signal "GND4")
		(24 "In11.Cu" signal "IN4")
		(26 "In12.Cu" signal "GND5")
		(28 "In13.Cu" signal "IN5")
		(30 "In14.Cu" signal "GND6")
		(32 "In15.Cu" signal "IN6")
		(34 "In16.Cu" signal "GND7")
		(2 "B.Cu" signal "BOTTOM")
		(9 "F.Adhes" user "F.Adhesive")
		(11 "B.Adhes" user "B.Adhesive")
		(13 "F.Paste" user "Package Geometry/Pastemask Top")
		(15 "B.Paste" user "Package Geometry/Pastemask Bottom")
		(5 "F.SilkS" user "Ref Des/Silkscreen Top")
		(7 "B.SilkS" user "Ref Des/Silkscreen Bottom")
		(1 "F.Mask" user "Board Geometry/Soldermask Top")
		(3 "B.Mask" user "Board Geometry/Soldermask Bottom")
		(17 "Dwgs.User" user "User.Drawings")
		(19 "Cmts.User" user "User.Comments")
		(21 "Eco1.User" user "User.Eco1")
		(23 "Eco2.User" user "User.Eco2")
		(25 "Edge.Cuts" user "Board Geometry/Outline")
		(27 "Margin" user)
		(31 "F.CrtYd" user "Package Geometry/Place Bound Top")
		(29 "B.CrtYd" user "Package Geometry/Place Bound Bottom")
		(35 "F.Fab" user "Ref Des/Assembly Top")
		(33 "B.Fab" user "Ref Des/Assembly Bottom")
	)
	(footprint ""
		(layer "B.Cu")
		(at 23.240746 -321.554856 -90)
		(property "Reference" "C64"
			(at 0 0 90)
			(layer "B.SilkS")
			(hide yes)
			(effects
				(font
					(size 1.27 1.27)
				)
				(justify mirror)
			)
		)
		(property "Value" ""
			(at 0 0 90)
			(layer "B.Fab")
			(effects
				(font
					(size 1.27 1.27)
				)
				(justify mirror)
			)
		)
		(duplicate_pad_numbers_are_jumpers no)
		(fp_line
			(start -1.524 0.762)
			(end 1.524 0.762)
			(stroke
				(width 0.1524)
				(type default)
			)
			(layer "B.SilkS")
		)
		(fp_line
			(start 1.524 0.762)
			(end 1.524 -0.762)
			(stroke
				(width 0.1524)
				(type default)
			)
			(layer "B.SilkS")
		)
		(fp_line
			(start -1.524 -0.762)
			(end -1.524 0.762)
			(stroke
				(width 0.1524)
				(type default)
			)
			(layer "B.SilkS")
		)
		(fp_line
			(start 1.524 -0.762)
			(end -1.524 -0.762)
			(stroke
				(width 0.1524)
				(type default)
			)
			(layer "B.SilkS")
		)
		(fp_line
			(start -1.1049 0.724916)
			(end -1.1049 -0.724916)
			(stroke
				(width 0.1)
				(type default)
			)
			(layer "B.Fab")
		)
		(fp_line
			(start 1.1049 0.724916)
			(end -1.1049 0.724916)
			(stroke
				(width 0.1)
				(type default)
			)
			(layer "B.Fab")
		)
		(fp_line
			(start -1.1049 -0.724916)
			(end 1.1049 -0.724916)
			(stroke
				(width 0.1)
				(type default)
			)
			(layer "B.Fab")
		)
		(fp_line
			(start 1.1049 -0.724916)
			(end 1.1049 0.724916)
			(stroke
				(width 0.1)
				(type default)
			)
			(layer "B.Fab")
		)
		(pad "1" smd rect
			(at 0.889 0 270)
			(size 1.016 1.27)
			(layers "B.Cu" "B.Mask" "B.Paste")
			(net "P12V_S3_AUX_CPU1_NVDIMM")
		)
		(pad "2" smd rect
			(at -0.889 0 270)
			(size 1.016 1.27)
			(layers "B.Cu" "B.Mask" "B.Paste")
			(net "GND")
		)
	)
	(footprint ""
		(layer "B.Cu")
		(at 329.240388 8.003794)
		(property "Reference" "J120"
			(at 4.361942 1.648206 270)
			(unlocked yes)
			(layer "B.SilkS")
			(effects
				(font
					(size 0.7874 0.5842)
					(thickness 0.1524)
				)
				(justify left mirror)
			)
		)
		(property "Value" ""
			(at 0 0 0)
			(layer "B.Fab")
			(effects
				(font
					(size 1.27 1.27)
				)
				(justify mirror)
			)
		)
		(duplicate_pad_numbers_are_jumpers no)
		(fp_line
			(start -1.2192 -2.1082)
			(end -1.2192 2.1082)
			(stroke
				(width 0.1524)
				(type default)
			)
			(layer "B.SilkS")
		)
		(fp_line
			(start -1.2192 2.1082)
			(end 1.2192 2.1082)
			(stroke
				(width 0.1524)
				(type default)
			)
			(layer "B.SilkS")
		)
		(fp_line
			(start 1.2192 -2.1082)
			(end -1.2192 -2.1082)
			(stroke
				(width 0.1524)
				(type default)
			)
			(layer "B.SilkS")
		)
		(fp_line
			(start 1.2192 2.1082)
			(end 1.2192 -2.1082)
			(stroke
				(width 0.1524)
				(type default)
			)
			(layer "B.SilkS")
		)
		(pad "" np_thru_hole circle
			(at -3.4671 -1.27 270)
			(size 1.0414 1.0414)
			(drill 1.0414)
			(layers "*.Cu" "*.Mask")
			(clearance 0.381)
			(thermal_gap 0.381)
		)
		(pad "" np_thru_hole circle
			(at -3.4671 1.27 270)
			(size 1.0414 1.0414)
			(drill 1.0414)
			(layers "*.Cu" "*.Mask")
			(clearance 0.381)
			(thermal_gap 0.381)
		)
		(pad "" np_thru_hole circle
			(at 2.8829 -1.27 270)
			(size 1.0414 1.0414)
			(drill 1.0414)
			(layers "*.Cu" "*.Mask")
			(clearance 0.381)
			(thermal_gap 0.381)
		)
		(pad "" np_thru_hole circle
			(at 2.8829 1.27 270)
			(size 1.0414 1.0414)
			(drill 1.0414)
			(layers "*.Cu" "*.Mask")
			(clearance 0.381)
			(thermal_gap 0.381)
		)
		(pad "1" smd rect
			(at -0.8255 -0.249936 270)
			(size 0.3048 0.508)
			(layers "B.Cu" "B.Mask" "B.Paste")
			(net "DELTA_L_85_10INCH_IN5_DN")
		)
		(pad "2" smd rect
			(at -0.8255 0.249936 270)
			(size 0.3048 0.508)
			(layers "B.Cu" "B.Mask" "B.Paste")
			(net "DELTA_L_85_10INCH_IN5_DP")
		)
		(pad "3" smd circle
			(at 0 0 180)
			(size 0 0)
			(layers "B.Cu" "B.Mask" "B.Paste")
			(net "DELTA_L_GND_1")
		)
		(zone
			(layers "F.Cu" "B.Cu" "In1.Cu" "In2.Cu" "In3.Cu" "In4.Cu" "In5.Cu" "In6.Cu"
				"In7.Cu" "In8.Cu" "In9.Cu" "In10.Cu" "In11.Cu" "In12.Cu" "In13.Cu" "In14.Cu"
				"In15.Cu" "In16.Cu"
			)
			(hatch none 0.5)
			(connect_pads
				(clearance 0)
			)
			(min_thickness 0.25)
			(keepout
				(tracks not_allowed)
				(vias allowed)
				(pads allowed)
				(copperpour not_allowed)
				(footprints allowed)
			)
			(placement
				(enabled no)
				(sheetname "")
			)
			(fill
				(thermal_gap 0.5)
				(thermal_bridge_width 0.5)
				(island_removal_mode 0)
			)
			(polygon
				(pts
					(arc
						(start 326.700388 6.733794)
						(mid 324.846188 6.733794)
						(end 326.700388 6.733794)
					)
				)
			)
		)
		(zone
			(layers "F.Cu" "B.Cu" "In1.Cu" "In2.Cu" "In3.Cu" "In4.Cu" "In5.Cu" "In6.Cu"
				"In7.Cu" "In8.Cu" "In9.Cu" "In10.Cu" "In11.Cu" "In12.Cu" "In13.Cu" "In14.Cu"
				"In15.Cu" "In16.Cu"
			)
			(hatch none 0.5)
			(connect_pads
				(clearance 0)
			)
			(min_thickness 0.25)
			(keepout
				(tracks not_allowed)
				(vias allowed)
				(pads allowed)
				(copperpour not_allowed)
				(footprints allowed)
			)
			(placement
				(enabled no)
				(sheetname "")
			)
			(fill
				(thermal_gap 0.5)
				(thermal_bridge_width 0.5)
				(island_removal_mode 0)
			)
			(polygon
				(pts
					(arc
						(start 326.700388 9.273794)
						(mid 324.846188 9.273794)
						(end 326.700388 9.273794)
					)
				)
			)
		)
		(zone
			(layers "F.Cu" "B.Cu" "In1.Cu" "In2.Cu" "In3.Cu" "In4.Cu" "In5.Cu" "In6.Cu"
				"In7.Cu" "In8.Cu" "In9.Cu" "In10.Cu" "In11.Cu" "In12.Cu" "In13.Cu" "In14.Cu"
				"In15.Cu" "In16.Cu"
			)
			(hatch none 0.5)
			(connect_pads
				(clearance 0)
			)
			(min_thickness 0.25)
			(keepout
				(tracks not_allowed)
				(vias allowed)
				(pads allowed)
				(copperpour not_allowed)
				(footprints allowed)
			)
			(placement
				(enabled no)
				(sheetname "")
			)
			(fill
				(thermal_gap 0.5)
				(thermal_bridge_width 0.5)
				(island_removal_mode 0)
			)
			(polygon
				(pts
					(arc
						(start 333.050388 6.733794)
						(mid 331.196188 6.733794)
						(end 333.050388 6.733794)
					)
				)
			)
		)
		(zone
			(layers "F.Cu" "B.Cu" "In1.Cu" "In2.Cu" "In3.Cu" "In4.Cu" "In5.Cu" "In6.Cu"
				"In7.Cu" "In8.Cu" "In9.Cu" "In10.Cu" "In11.Cu" "In12.Cu" "In13.Cu" "In14.Cu"
				"In15.Cu" "In16.Cu"
			)
			(hatch none 0.5)
			(connect_pads
				(clearance 0)
			)
			(min_thickness 0.25)
			(keepout
				(tracks not_allowed)
				(vias allowed)
				(pads allowed)
				(copperpour not_allowed)
				(footprints allowed)
			)
			(placement
				(enabled no)
				(sheetname "")
			)
			(fill
				(thermal_gap 0.5)
				(thermal_bridge_width 0.5)
				(island_removal_mode 0)
			)
			(polygon
				(pts
					(arc
						(start 333.050388 9.273794)
						(mid 331.196188 9.273794)
						(end 333.050388 9.273794)
					)
				)
			)
		)
		(zone
			(layer "B.Cu")
			(hatch none 0.5)
			(connect_pads
				(clearance 0)
			)
			(min_thickness 0.25)
			(keepout
				(tracks not_allowed)
				(vias allowed)
				(pads allowed)
				(copperpour not_allowed)
				(footprints allowed)
			)
			(placement
				(enabled no)
				(sheetname "")
			)
			(fill
				(thermal_gap 0.5)
				(thermal_bridge_width 0.5)
				(island_removal_mode 0)
			)
			(polygon
				(pts
					(xy 328.122788 7.455154) (xy 328.122788 7.550658) (xy 328.719688 7.550658) (xy 328.719688 7.957058)
					(xy 328.122788 7.957058) (xy 328.122788 8.05053) (xy 328.719688 8.05053) (xy 328.719688 8.45693)
					(xy 328.122788 8.45693) (xy 328.122788 8.552434) (xy 328.821288 8.552434) (xy 328.821288 7.455154)
				)
			)
		)
	)
)
